(kicad_pcb
	(version 20260206)
	(generator "pcbnew")
	(generator_version "10.0")
	(general
		(thickness 1.6)
		(legacy_teardrops no)
	)
	(paper "A4")
	(title_block
		(title "03242023_DA0F0TMBIJ0_F0T_Motherboard_J_brd_V01_OCP.brd")
		(comment 1 "Grand Teton / footprints 2366-2371 of 6105")
	)
	(layers
		(0 "F.Cu" signal "TOP")
		(4 "In1.Cu" signal "GND")
		(6 "In2.Cu" signal "IN1")
		(8 "In3.Cu" signal "GND1")
		(10 "In4.Cu" signal "IN2")
		(12 "In5.Cu" signal "GND2")
		(14 "In6.Cu" signal "IN3")
		(16 "In7.Cu" signal "GND3")
		(18 "In8.Cu" signal "VCC")
		(20 "In9.Cu" signal "VCC1")
		(22 "In10.Cu" signal "GND4")
		(24 "In11.Cu" signal "IN4")
		(26 "In12.Cu" signal "GND5")
		(28 "In13.Cu" signal "IN5")
		(30 "In14.Cu" signal "GND6")
		(32 "In15.Cu" signal "IN6")
		(34 "In16.Cu" signal "GND7")
		(2 "B.Cu" signal "BOTTOM")
		(9 "F.Adhes" user "F.Adhesive")
		(11 "B.Adhes" user "B.Adhesive")
		(13 "F.Paste" user "Package Geometry/Pastemask Top")
		(15 "B.Paste" user "Package Geometry/Pastemask Bottom")
		(5 "F.SilkS" user "Ref Des/Silkscreen Top")
		(7 "B.SilkS" user "Ref Des/Silkscreen Bottom")
		(1 "F.Mask" user "Board Geometry/Soldermask Top")
		(3 "B.Mask" user "Board Geometry/Soldermask Bottom")
		(17 "Dwgs.User" user "User.Drawings")
		(19 "Cmts.User" user "User.Comments")
		(21 "Eco1.User" user "User.Eco1")
		(23 "Eco2.User" user "User.Eco2")
		(25 "Edge.Cuts" user "Board Geometry/Outline")
		(27 "Margin" user)
		(31 "F.CrtYd" user "Package Geometry/Place Bound Top")
		(29 "B.CrtYd" user "Package Geometry/Place Bound Bottom")
		(35 "F.Fab" user "Ref Des/Assembly Top")
		(33 "B.Fab" user "Ref Des/Assembly Bottom")
	)
	(footprint ""
		(layer "F.Cu")
		(at 23.760938 -174.53483 90)
		(property "Reference" "PC2277"
			(at 0 0 90)
			(layer "F.SilkS")
			(hide yes)
			(effects
				(font
					(size 1.27 1.27)
				)
			)
		)
		(property "Value" ""
			(at 0 0 90)
			(layer "F.Fab")
			(effects
				(font
					(size 1.27 1.27)
				)
			)
		)
		(duplicate_pad_numbers_are_jumpers no)
		(fp_line
			(start 0.7874 -0.4064)
			(end 0.7874 0.4064)
			(stroke
				(width 0.1524)
				(type default)
			)
			(layer "F.SilkS")
		)
		(fp_line
			(start -0.7874 -0.4064)
			(end 0.7874 -0.4064)
			(stroke
				(width 0.1524)
				(type default)
			)
			(layer "F.SilkS")
		)
		(fp_line
			(start 0.7874 0.4064)
			(end -0.7874 0.4064)
			(stroke
				(width 0.1524)
				(type default)
			)
			(layer "F.SilkS")
		)
		(fp_line
			(start -0.7874 0.4064)
			(end -0.7874 -0.4064)
			(stroke
				(width 0.1524)
				(type default)
			)
			(layer "F.SilkS")
		)
		(fp_line
			(start -0.12065 -0.305054)
			(end -0.12065 -0.2794)
			(stroke
				(width 0.1)
				(type default)
			)
			(layer "F.Fab")
		)
		(fp_line
			(start -0.67945 -0.305054)
			(end -0.12065 -0.305054)
			(stroke
				(width 0.1)
				(type default)
			)
			(layer "F.Fab")
		)
		(fp_line
			(start 0.67945 -0.3048)
			(end 0.67945 0.3048)
			(stroke
				(width 0.1)
				(type default)
			)
			(layer "F.Fab")
		)
		(fp_line
			(start 0.12065 -0.3048)
			(end 0.67945 -0.3048)
			(stroke
				(width 0.1)
				(type default)
			)
			(layer "F.Fab")
		)
		(fp_line
			(start 0.12065 -0.2794)
			(end 0.12065 -0.3048)
			(stroke
				(width 0.1)
				(type default)
			)
			(layer "F.Fab")
		)
		(fp_line
			(start -0.12065 -0.2794)
			(end 0.12065 -0.2794)
			(stroke
				(width 0.1)
				(type default)
			)
			(layer "F.Fab")
		)
		(fp_line
			(start 0.120396 0.2794)
			(end -0.12065 0.2794)
			(stroke
				(width 0.1)
				(type default)
			)
			(layer "F.Fab")
		)
		(fp_line
			(start -0.12065 0.2794)
			(end -0.12065 0.3048)
			(stroke
				(width 0.1)
				(type default)
			)
			(layer "F.Fab")
		)
		(fp_line
			(start 0.67945 0.3048)
			(end 0.120396 0.3048)
			(stroke
				(width 0.1)
				(type default)
			)
			(layer "F.Fab")
		)
		(fp_line
			(start 0.120396 0.3048)
			(end 0.120396 0.2794)
			(stroke
				(width 0.1)
				(type default)
			)
			(layer "F.Fab")
		)
		(fp_line
			(start -0.12065 0.3048)
			(end -0.67945 0.3048)
			(stroke
				(width 0.1)
				(type default)
			)
			(layer "F.Fab")
		)
		(fp_line
			(start -0.67945 0.3048)
			(end -0.67945 -0.305054)
			(stroke
				(width 0.1)
				(type default)
			)
			(layer "F.Fab")
		)
		(pad "1" smd circle
			(at -0.40005 0 90)
			(size 0 0)
			(layers "F.Cu" "F.Mask" "F.Paste")
			(net "PVNN_MAIN_CPU1_FB_RC")
		)
		(pad "2" smd circle
			(at 0.40005 0 90)
			(size 0 0)
			(layers "F.Cu" "F.Mask" "F.Paste")
			(net "GND")
		)
	)
	(footprint ""
		(layer "F.Cu")
		(at 156.053536 -31.341568 90)
		(property "Reference" "R4452"
			(at 0 0 90)
			(layer "F.SilkS")
			(hide yes)
			(effects
				(font
					(size 1.27 1.27)
				)
			)
		)
		(property "Value" ""
			(at 0 0 90)
			(layer "F.Fab")
			(effects
				(font
					(size 1.27 1.27)
				)
			)
		)
		(duplicate_pad_numbers_are_jumpers no)
		(fp_line
			(start 0.7874 -0.4064)
			(end 0.7874 0.4064)
			(stroke
				(width 0.1524)
				(type default)
			)
			(layer "F.SilkS")
		)
		(fp_line
			(start -0.7874 -0.4064)
			(end 0.7874 -0.4064)
			(stroke
				(width 0.1524)
				(type default)
			)
			(layer "F.SilkS")
		)
		(fp_line
			(start 0.7874 0.4064)
			(end -0.7874 0.4064)
			(stroke
				(width 0.1524)
				(type default)
			)
			(layer "F.SilkS")
		)
		(fp_line
			(start -0.7874 0.4064)
			(end -0.7874 -0.4064)
			(stroke
				(width 0.1524)
				(type default)
			)
			(layer "F.SilkS")
		)
		(fp_line
			(start -0.12065 -0.305054)
			(end -0.12065 -0.2794)
			(stroke
				(width 0.1)
				(type default)
			)
			(layer "F.Fab")
		)
		(fp_line
			(start -0.67945 -0.305054)
			(end -0.12065 -0.305054)
			(stroke
				(width 0.1)
				(type default)
			)
			(layer "F.Fab")
		)
		(fp_line
			(start 0.67945 -0.3048)
			(end 0.67945 0.3048)
			(stroke
				(width 0.1)
				(type default)
			)
			(layer "F.Fab")
		)
		(fp_line
			(start 0.12065 -0.3048)
			(end 0.67945 -0.3048)
			(stroke
				(width 0.1)
				(type default)
			)
			(layer "F.Fab")
		)
		(fp_line
			(start 0.12065 -0.2794)
			(end 0.12065 -0.3048)
			(stroke
				(width 0.1)
				(type default)
			)
			(layer "F.Fab")
		)
		(fp_line
			(start -0.12065 -0.2794)
			(end 0.12065 -0.2794)
			(stroke
				(width 0.1)
				(type default)
			)
			(layer "F.Fab")
		)
		(fp_line
			(start 0.120396 0.2794)
			(end -0.12065 0.2794)
			(stroke
				(width 0.1)
				(type default)
			)
			(layer "F.Fab")
		)
		(fp_line
			(start -0.12065 0.2794)
			(end -0.12065 0.3048)
			(stroke
				(width 0.1)
				(type default)
			)
			(layer "F.Fab")
		)
		(fp_line
			(start 0.67945 0.3048)
			(end 0.120396 0.3048)
			(stroke
				(width 0.1)
				(type default)
			)
			(layer "F.Fab")
		)
		(fp_line
			(start 0.120396 0.3048)
			(end 0.120396 0.2794)
			(stroke
				(width 0.1)
				(type default)
			)
			(layer "F.Fab")
		)
		(fp_line
			(start -0.12065 0.3048)
			(end -0.67945 0.3048)
			(stroke
				(width 0.1)
				(type default)
			)
			(layer "F.Fab")
		)
		(fp_line
			(start -0.67945 0.3048)
			(end -0.67945 -0.305054)
			(stroke
				(width 0.1)
				(type default)
			)
			(layer "F.Fab")
		)
		(pad "1" smd circle
			(at -0.40005 0 90)
			(size 0 0)
			(layers "F.Cu" "F.Mask" "F.Paste")
			(net "P3V3_AUX")
		)
		(pad "2" smd circle
			(at 0.40005 0 90)
			(size 0 0)
			(layers "F.Cu" "F.Mask" "F.Paste")
			(net "RST_USB_HUB_2_R_N")
		)
	)
	(footprint ""
		(layer "F.Cu")
		(at 348.961964 -66.988944)
		(property "Reference" "C146"
			(at 0 0 0)
			(layer "F.SilkS")
			(hide yes)
			(effects
				(font
					(size 1.27 1.27)
				)
			)
		)
		(property "Value" ""
			(at 0 0 0)
			(layer "F.Fab")
			(effects
				(font
					(size 1.27 1.27)
				)
			)
		)
		(duplicate_pad_numbers_are_jumpers no)
		(fp_line
			(start -0.299974 -0.150114)
			(end 0.299974 -0.150114)
			(stroke
				(width 0.1)
				(type default)
			)
			(layer "F.Fab")
		)
		(fp_line
			(start -0.299974 0.150114)
			(end -0.299974 -0.150114)
			(stroke
				(width 0.1)
				(type default)
			)
			(layer "F.Fab")
		)
		(fp_line
			(start 0.299974 -0.150114)
			(end 0.299974 0.150114)
			(stroke
				(width 0.1)
				(type default)
			)
			(layer "F.Fab")
		)
		(fp_line
			(start 0.299974 0.150114)
			(end -0.299974 0.150114)
			(stroke
				(width 0.1)
				(type default)
			)
			(layer "F.Fab")
		)
		(pad "1" smd rect
			(at -0.2667 0)
			(size 0.3048 0.381)
			(layers "F.Cu" "F.Mask" "F.Paste")
			(net "DMI_CPU0_PCH_TX_C_DP<4>")
		)
		(pad "2" smd rect
			(at 0.2667 0)
			(size 0.3048 0.381)
			(layers "F.Cu" "F.Mask" "F.Paste")
			(net "DMI_CPU0_PCH_TX_DP<4>")
		)
		(zone
			(layer "In1.Cu")
			(hatch none 0.5)
			(connect_pads
				(clearance 0)
			)
			(min_thickness 0.25)
			(keepout
				(tracks not_allowed)
				(vias allowed)
				(pads allowed)
				(copperpour not_allowed)
				(footprints allowed)
			)
			(placement
				(enabled no)
				(sheetname "")
			)
			(fill
				(thermal_gap 0.5)
				(thermal_bridge_width 0.5)
				(island_removal_mode 0)
			)
			(polygon
				(pts
					(arc
						(start 348.568264 -66.747644)
						(mid 348.514382 -66.769962)
						(end 348.492064 -66.823844)
					)
					(arc
						(start 348.492064 -67.154044)
						(mid 348.514382 -67.207926)
						(end 348.568264 -67.230244)
					)
					(arc
						(start 348.822264 -67.230244)
						(mid 348.876146 -67.207926)
						(end 348.898464 -67.154044)
					)
					(arc
						(start 348.898464 -66.823844)
						(mid 348.876146 -66.769962)
						(end 348.822264 -66.747644)
					)
				)
			)
		)
		(zone
			(layer "In1.Cu")
			(hatch none 0.5)
			(connect_pads
				(clearance 0)
			)
			(min_thickness 0.25)
			(keepout
				(tracks not_allowed)
				(vias allowed)
				(pads allowed)
				(copperpour not_allowed)
				(footprints allowed)
			)
			(placement
				(enabled no)
				(sheetname "")
			)
			(fill
				(thermal_gap 0.5)
				(thermal_bridge_width 0.5)
				(island_removal_mode 0)
			)
			(polygon
				(pts
					(arc
						(start 349.101664 -66.747644)
						(mid 349.047782 -66.769962)
						(end 349.025464 -66.823844)
					)
					(arc
						(start 349.025464 -67.154044)
						(mid 349.047782 -67.207926)
						(end 349.101664 -67.230244)
					)
					(arc
						(start 349.355664 -67.230244)
						(mid 349.409546 -67.207926)
						(end 349.431864 -67.154044)
					)
					(arc
						(start 349.431864 -66.823844)
						(mid 349.409546 -66.769962)
						(end 349.355664 -66.747644)
					)
				)
			)
		)
	)
	(footprint ""
		(layer "F.Cu")
		(at 428.226474 -126.81966)
		(property "Reference" "PR358"
			(at 0 0 0)
			(layer "F.SilkS")
			(hide yes)
			(effects
				(font
					(size 1.27 1.27)
				)
			)
		)
		(property "Value" ""
			(at 0 0 0)
			(layer "F.Fab")
			(effects
				(font
					(size 1.27 1.27)
				)
			)
		)
		(duplicate_pad_numbers_are_jumpers no)
		(fp_line
			(start -0.7874 -0.4064)
			(end 0.7874 -0.4064)
			(stroke
				(width 0.1524)
				(type default)
			)
			(layer "F.SilkS")
		)
		(fp_line
			(start -0.7874 0.4064)
			(end -0.7874 -0.4064)
			(stroke
				(width 0.1524)
				(type default)
			)
			(layer "F.SilkS")
		)
		(fp_line
			(start 0.7874 -0.4064)
			(end 0.7874 0.4064)
			(stroke
				(width 0.1524)
				(type default)
			)
			(layer "F.SilkS")
		)
		(fp_line
			(start 0.7874 0.4064)
			(end -0.7874 0.4064)
			(stroke
				(width 0.1524)
				(type default)
			)
			(layer "F.SilkS")
		)
		(fp_line
			(start -0.67945 -0.305054)
			(end -0.12065 -0.305054)
			(stroke
				(width 0.1)
				(type default)
			)
			(layer "F.Fab")
		)
		(fp_line
			(start -0.67945 0.3048)
			(end -0.67945 -0.305054)
			(stroke
				(width 0.1)
				(type default)
			)
			(layer "F.Fab")
		)
		(fp_line
			(start -0.12065 -0.305054)
			(end -0.12065 -0.2794)
			(stroke
				(width 0.1)
				(type default)
			)
			(layer "F.Fab")
		)
		(fp_line
			(start -0.12065 -0.2794)
			(end 0.12065 -0.2794)
			(stroke
				(width 0.1)
				(type default)
			)
			(layer "F.Fab")
		)
		(fp_line
			(start -0.12065 0.2794)
			(end -0.12065 0.3048)
			(stroke
				(width 0.1)
				(type default)
			)
			(layer "F.Fab")
		)
		(fp_line
			(start -0.12065 0.3048)
			(end -0.67945 0.3048)
			(stroke
				(width 0.1)
				(type default)
			)
			(layer "F.Fab")
		)
		(fp_line
			(start 0.120396 0.2794)
			(end -0.12065 0.2794)
			(stroke
				(width 0.1)
				(type default)
			)
			(layer "F.Fab")
		)
		(fp_line
			(start 0.120396 0.3048)
			(end 0.120396 0.2794)
			(stroke
				(width 0.1)
				(type default)
			)
			(layer "F.Fab")
		)
		(fp_line
			(start 0.12065 -0.3048)
			(end 0.67945 -0.3048)
			(stroke
				(width 0.1)
				(type default)
			)
			(layer "F.Fab")
		)
		(fp_line
			(start 0.12065 -0.2794)
			(end 0.12065 -0.3048)
			(stroke
				(width 0.1)
				(type default)
			)
			(layer "F.Fab")
		)
		(fp_line
			(start 0.67945 -0.3048)
			(end 0.67945 0.3048)
			(stroke
				(width 0.1)
				(type default)
			)
			(layer "F.Fab")
		)
		(fp_line
			(start 0.67945 0.3048)
			(end 0.120396 0.3048)
			(stroke
				(width 0.1)
				(type default)
			)
			(layer "F.Fab")
		)
		(pad "1" smd circle
			(at -0.40005 0)
			(size 0 0)
			(layers "F.Cu" "F.Mask" "F.Paste")
			(net "GND")
		)
		(pad "2" smd circle
			(at 0.40005 0)
			(size 0 0)
			(layers "F.Cu" "F.Mask" "F.Paste")
			(net "PVCCD_HV_CPU0_ADDR")
		)
	)
	(footprint ""
		(layer "F.Cu")
		(at 167.064944 -353.76358)
		(property "Reference" "PR703"
			(at 0 0 0)
			(layer "F.SilkS")
			(hide yes)
			(effects
				(font
					(size 1.27 1.27)
				)
			)
		)
		(property "Value" ""
			(at 0 0 0)
			(layer "F.Fab")
			(effects
				(font
					(size 1.27 1.27)
				)
			)
		)
		(duplicate_pad_numbers_are_jumpers no)
		(fp_line
			(start -0.7874 -0.4064)
			(end 0.7874 -0.4064)
			(stroke
				(width 0.1524)
				(type default)
			)
			(layer "F.SilkS")
		)
		(fp_line
			(start -0.7874 0.4064)
			(end -0.7874 -0.4064)
			(stroke
				(width 0.1524)
				(type default)
			)
			(layer "F.SilkS")
		)
		(fp_line
			(start 0.7874 -0.4064)
			(end 0.7874 0.4064)
			(stroke
				(width 0.1524)
				(type default)
			)
			(layer "F.SilkS")
		)
		(fp_line
			(start 0.7874 0.4064)
			(end -0.7874 0.4064)
			(stroke
				(width 0.1524)
				(type default)
			)
			(layer "F.SilkS")
		)
		(fp_line
			(start -0.67945 -0.305054)
			(end -0.12065 -0.305054)
			(stroke
				(width 0.1)
				(type default)
			)
			(layer "F.Fab")
		)
		(fp_line
			(start -0.67945 0.3048)
			(end -0.67945 -0.305054)
			(stroke
				(width 0.1)
				(type default)
			)
			(layer "F.Fab")
		)
		(fp_line
			(start -0.12065 -0.305054)
			(end -0.12065 -0.2794)
			(stroke
				(width 0.1)
				(type default)
			)
			(layer "F.Fab")
		)
		(fp_line
			(start -0.12065 -0.2794)
			(end 0.12065 -0.2794)
			(stroke
				(width 0.1)
				(type default)
			)
			(layer "F.Fab")
		)
		(fp_line
			(start -0.12065 0.2794)
			(end -0.12065 0.3048)
			(stroke
				(width 0.1)
				(type default)
			)
			(layer "F.Fab")
		)
		(fp_line
			(start -0.12065 0.3048)
			(end -0.67945 0.3048)
			(stroke
				(width 0.1)
				(type default)
			)
			(layer "F.Fab")
		)
		(fp_line
			(start 0.120396 0.2794)
			(end -0.12065 0.2794)
			(stroke
				(width 0.1)
				(type default)
			)
			(layer "F.Fab")
		)
		(fp_line
			(start 0.120396 0.3048)
			(end 0.120396 0.2794)
			(stroke
				(width 0.1)
				(type default)
			)
			(layer "F.Fab")
		)
		(fp_line
			(start 0.12065 -0.3048)
			(end 0.67945 -0.3048)
			(stroke
				(width 0.1)
				(type default)
			)
			(layer "F.Fab")
		)
		(fp_line
			(start 0.12065 -0.2794)
			(end 0.12065 -0.3048)
			(stroke
				(width 0.1)
				(type default)
			)
			(layer "F.Fab")
		)
		(fp_line
			(start 0.67945 -0.3048)
			(end 0.67945 0.3048)
			(stroke
				(width 0.1)
				(type default)
			)
			(layer "F.Fab")
		)
		(fp_line
			(start 0.67945 0.3048)
			(end 0.120396 0.3048)
			(stroke
				(width 0.1)
				(type default)
			)
			(layer "F.Fab")
		)
		(pad "1" smd circle
			(at -0.40005 0)
			(size 0 0)
			(layers "F.Cu" "F.Mask" "F.Paste")
			(net "P3V3")
		)
		(pad "2" smd circle
			(at 0.40005 0)
			(size 0 0)
			(layers "F.Cu" "F.Mask" "F.Paste")
			(net "PVCCFA_EHV_FIVRA_CPU1_PVCC1")
		)
	)
	(footprint ""
		(layer "F.Cu")
		(at 136.07288 -46.065948)
		(property "Reference" "Q95"
			(at -1.4224 -1.768348 0)
			(unlocked yes)
			(layer "F.SilkS")
			(effects
				(font
					(size 0.7874 0.5842)
					(thickness 0.1524)
				)
				(justify left)
			)
		)
		(property "Value" ""
			(at 0 0 0)
			(layer "F.Fab")
			(effects
				(font
					(size 1.27 1.27)
				)
			)
		)
		(duplicate_pad_numbers_are_jumpers no)
		(fp_line
			(start -1.332738 -1.100074)
			(end -0.4826 -1.100074)
			(stroke
				(width 0.1524)
				(type default)
			)
			(layer "F.SilkS")
		)
		(fp_line
			(start -1.332738 1.100074)
			(end -1.332738 -1.100074)
			(stroke
				(width 0.1524)
				(type default)
			)
			(layer "F.SilkS")
		)
		(fp_line
			(start -0.4826 -1.100074)
			(end 0 -0.541274)
			(stroke
				(width 0.1524)
				(type default)
			)
			(layer "F.SilkS")
		)
		(fp_line
			(start 0 -0.541274)
			(end 0.4826 -1.100074)
			(stroke
				(width 0.1524)
				(type default)
			)
			(layer "F.SilkS")
		)
		(fp_line
			(start 0.4826 -1.100074)
			(end 1.332738 -1.100074)
			(stroke
				(width 0.1524)
				(type default)
			)
			(layer "F.SilkS")
		)
		(fp_line
			(start 1.332738 -1.100074)
			(end 1.332738 1.100074)
			(stroke
				(width 0.1524)
				(type default)
			)
			(layer "F.SilkS")
		)
		(fp_line
			(start 1.332738 1.100074)
			(end -1.332738 1.100074)
			(stroke
				(width 0.1524)
				(type default)
			)
			(layer "F.SilkS")
		)
		(fp_poly
			(pts
				(xy -2.2352 -1.001014) (xy -1.533144 -0.649986) (xy -2.2352 -0.298958)
			)
			(stroke
				(width 0)
				(type default)
			)
			(fill yes)
			(layer "F.SilkS")
		)
		(fp_line
			(start -0.674878 -1.100074)
			(end 0.674878 -1.100074)
			(stroke
				(width 0.1)
				(type default)
			)
			(layer "F.Fab")
		)
		(fp_line
			(start -0.674878 1.100074)
			(end -0.674878 -1.100074)
			(stroke
				(width 0.1)
				(type default)
			)
			(layer "F.Fab")
		)
		(fp_line
			(start 0.674878 -1.100074)
			(end 0.674878 1.100074)
			(stroke
				(width 0.1)
				(type default)
			)
			(layer "F.Fab")
		)
		(fp_line
			(start 0.674878 1.100074)
			(end -0.674878 1.100074)
			(stroke
				(width 0.1)
				(type default)
			)
			(layer "F.Fab")
		)
		(fp_poly
			(pts
				(xy -2.2352 -0.298958) (xy -2.2352 -1.001014) (xy -1.533144 -0.649986)
			)
			(stroke
				(width 0)
				(type default)
			)
			(fill yes)
			(layer "F.Fab")
		)
		(pad "1" smd rect
			(at -0.94996 -0.649986 90)
			(size 0.4318 0.508)
			(layers "F.Cu" "F.Mask" "F.Paste")
			(net "GND")
		)
		(pad "2" smd rect
			(at -0.94996 0 90)
			(size 0.4318 0.508)
			(layers "F.Cu" "F.Mask" "F.Paste")
			(net "HDD_ACTIVITY_BUF")
		)
		(pad "3" smd rect
			(at -0.94996 0.649986 90)
			(size 0.4318 0.508)
			(layers "F.Cu" "F.Mask" "F.Paste")
			(net "NC_Q95_D2")
		)
		(pad "4" smd rect
			(at 0.94996 0.649986 90)
			(size 0.4318 0.508)
			(layers "F.Cu" "F.Mask" "F.Paste")
			(net "NC_Q95_S2")
		)
		(pad "5" smd rect
			(at 0.94996 0 90)
			(size 0.4318 0.508)
			(layers "F.Cu" "F.Mask" "F.Paste")
			(net "NC_Q95_G2")
		)
		(pad "6" smd rect
			(at 0.94996 -0.649986 90)
			(size 0.4318 0.508)
			(layers "F.Cu" "F.Mask" "F.Paste")
			(net "HDD_ACTIVITY_BUF_N")
		)
	)
)
